# T6G (Grand Teton) — schematic netlist excerpt (pin names and nets, part order shuffled) for the footprints in the layout excerpt that follows; sources: Cadence DE-HDL packaged netlist, KiCad conversion of 04192023_DAF0TMB3IC0_F0TG_MB_C_brd_V02_OCP.brd

R6106  Q_RES  10K 5% CHIP  pkg 0402LF  page 167 : A = PVDD18_S5_P0 ; B = FM_PASSWORD_CLEAR_N
L24  Q_INDUCTOR  BLM18PG300SN1D IND  pkg SMLF  page 258 : \1\ = P3V3_MAX11617_2_VDD ; \2\ = P3V3_AUX
C496  Q_CAP  0.1UF 10V 10% X7S  pkg C0201  page 356 : A = P0V9_CPU1_RT3_2A ; B = GND

(kicad_pcb
	(version 20260206)
	(generator "pcbnew")
	(generator_version "10.0")
	(general
		(thickness 1.6)
		(legacy_teardrops no)
	)
	(paper "A4")
	(title_block
		(title "04192023_DAF0TMB3IC0_F0TG_MB_C_brd_V02_OCP.brd")
		(comment 1 "Grand Teton / footprints 7828-7830 of 8354")
	)
	(layers
		(0 "F.Cu" signal "TOP")
		(4 "In1.Cu" signal "GND")
		(6 "In2.Cu" signal "IN1")
		(8 "In3.Cu" signal "GND1")
		(10 "In4.Cu" signal "IN2")
		(12 "In5.Cu" signal "GND2")
		(14 "In6.Cu" signal "IN3")
		(16 "In7.Cu" signal "GND3")
		(18 "In8.Cu" signal "VCC")
		(20 "In9.Cu" signal "VCC1")
		(22 "In10.Cu" signal "GND4")
		(24 "In11.Cu" signal "IN4")
		(26 "In12.Cu" signal "GND5")
		(28 "In13.Cu" signal "IN5")
		(30 "In14.Cu" signal "GND6")
		(32 "In15.Cu" signal "IN6")
		(34 "In16.Cu" signal "GND7")
		(2 "B.Cu" signal "BOTTOM")
		(9 "F.Adhes" user "F.Adhesive")
		(11 "B.Adhes" user "B.Adhesive")
		(13 "F.Paste" user "Package Geometry/Pastemask Top")
		(15 "B.Paste" user "Package Geometry/Pastemask Bottom")
		(5 "F.SilkS" user "Ref Des/Silkscreen Top")
		(7 "B.SilkS" user "Ref Des/Silkscreen Bottom")
		(1 "F.Mask" user "Board Geometry/Soldermask Top")
		(3 "B.Mask" user "Board Geometry/Soldermask Bottom")
		(17 "Dwgs.User" user "User.Drawings")
		(19 "Cmts.User" user "User.Comments")
		(21 "Eco1.User" user "User.Eco1")
		(23 "Eco2.User" user "User.Eco2")
		(25 "Edge.Cuts" user "Board Geometry/Outline")
		(27 "Margin" user)
		(31 "F.CrtYd" user "Package Geometry/Place Bound Top")
		(29 "B.CrtYd" user "Package Geometry/Place Bound Bottom")
		(35 "F.Fab" user "Ref Des/Assembly Top")
		(33 "B.Fab" user "Ref Des/Assembly Bottom")
	)
	(footprint ""
		(layer "B.Cu")
		(at 428.98695 -31.181548 180)
		(property "Reference" "R6106"
			(at 0 0 0)
			(layer "B.SilkS")
			(hide yes)
			(effects
				(font
					(size 1.27 1.27)
				)
				(justify mirror)
			)
		)
		(property "Value" ""
			(at 0 0 0)
			(layer "B.Fab")
			(effects
				(font
					(size 1.27 1.27)
				)
				(justify mirror)
			)
		)
		(duplicate_pad_numbers_are_jumpers no)
		(fp_line
			(start 0.7874 0.4064)
			(end 0.7874 -0.4064)
			(stroke
				(width 0.1524)
				(type default)
			)
			(layer "B.SilkS")
		)
		(fp_line
			(start 0.7874 -0.4064)
			(end -0.7874 -0.4064)
			(stroke
				(width 0.1524)
				(type default)
			)
			(layer "B.SilkS")
		)
		(fp_line
			(start -0.7874 0.4064)
			(end 0.7874 0.4064)
			(stroke
				(width 0.1524)
				(type default)
			)
			(layer "B.SilkS")
		)
		(fp_line
			(start -0.7874 -0.4064)
			(end -0.7874 0.4064)
			(stroke
				(width 0.1524)
				(type default)
			)
			(layer "B.SilkS")
		)
		(fp_line
			(start 0.67945 0.3048)
			(end 0.67945 -0.305054)
			(stroke
				(width 0.1)
				(type default)
			)
			(layer "B.Fab")
		)
		(fp_line
			(start 0.67945 -0.305054)
			(end 0.12065 -0.305054)
			(stroke
				(width 0.1)
				(type default)
			)
			(layer "B.Fab")
		)
		(fp_line
			(start 0.12065 0.3048)
			(end 0.67945 0.3048)
			(stroke
				(width 0.1)
				(type default)
			)
			(layer "B.Fab")
		)
		(fp_line
			(start 0.12065 0.2794)
			(end 0.12065 0.3048)
			(stroke
				(width 0.1)
				(type default)
			)
			(layer "B.Fab")
		)
		(fp_line
			(start 0.12065 -0.2794)
			(end -0.12065 -0.2794)
			(stroke
				(width 0.1)
				(type default)
			)
			(layer "B.Fab")
		)
		(fp_line
			(start 0.12065 -0.305054)
			(end 0.12065 -0.2794)
			(stroke
				(width 0.1)
				(type default)
			)
			(layer "B.Fab")
		)
		(fp_line
			(start -0.120396 0.3048)
			(end -0.120396 0.2794)
			(stroke
				(width 0.1)
				(type default)
			)
			(layer "B.Fab")
		)
		(fp_line
			(start -0.120396 0.2794)
			(end 0.12065 0.2794)
			(stroke
				(width 0.1)
				(type default)
			)
			(layer "B.Fab")
		)
		(fp_line
			(start -0.12065 -0.2794)
			(end -0.12065 -0.3048)
			(stroke
				(width 0.1)
				(type default)
			)
			(layer "B.Fab")
		)
		(fp_line
			(start -0.12065 -0.3048)
			(end -0.67945 -0.3048)
			(stroke
				(width 0.1)
				(type default)
			)
			(layer "B.Fab")
		)
		(fp_line
			(start -0.67945 0.3048)
			(end -0.120396 0.3048)
			(stroke
				(width 0.1)
				(type default)
			)
			(layer "B.Fab")
		)
		(fp_line
			(start -0.67945 -0.3048)
			(end -0.67945 0.3048)
			(stroke
				(width 0.1)
				(type default)
			)
			(layer "B.Fab")
		)
		(pad "1" smd circle
			(at 0.40005 0)
			(size 0 0)
			(layers "B.Cu" "B.Mask" "B.Paste")
			(net "PVDD18_S5_P0")
		)
		(pad "2" smd circle
			(at -0.40005 0)
			(size 0 0)
			(layers "B.Cu" "B.Mask" "B.Paste")
			(net "FM_PASSWORD_CLEAR_N")
		)
	)
	(footprint ""
		(layer "B.Cu")
		(at 242.062 -328.168)
		(property "Reference" "L24"
			(at 0 0 0)
			(layer "B.SilkS")
			(hide yes)
			(effects
				(font
					(size 1.27 1.27)
				)
				(justify mirror)
			)
		)
		(property "Value" ""
			(at 0 0 0)
			(layer "B.Fab")
			(effects
				(font
					(size 1.27 1.27)
				)
				(justify mirror)
			)
		)
		(duplicate_pad_numbers_are_jumpers no)
		(fp_line
			(start -1.27 0.5842)
			(end -1.27 -0.5842)
			(stroke
				(width 0.1524)
				(type default)
			)
			(layer "B.SilkS")
		)
		(fp_line
			(start -1.27 0.5842)
			(end 1.27 0.5842)
			(stroke
				(width 0.1524)
				(type default)
			)
			(layer "B.SilkS")
		)
		(fp_line
			(start 1.27 -0.5842)
			(end -1.27 -0.5842)
			(stroke
				(width 0.1524)
				(type default)
			)
			(layer "B.SilkS")
		)
		(fp_line
			(start 1.27 -0.5588)
			(end 1.27 -0.5842)
			(stroke
				(width 0.1524)
				(type default)
			)
			(layer "B.SilkS")
		)
		(fp_line
			(start 1.27 0.5842)
			(end 1.27 -0.5842)
			(stroke
				(width 0.1524)
				(type default)
			)
			(layer "B.SilkS")
		)
		(fp_line
			(start -1.1938 -0.406654)
			(end -1.1938 0.4064)
			(stroke
				(width 0.1)
				(type default)
			)
			(layer "B.Fab")
		)
		(fp_line
			(start -1.1938 0.4064)
			(end -0.9144 0.4064)
			(stroke
				(width 0.1)
				(type default)
			)
			(layer "B.Fab")
		)
		(fp_line
			(start -0.9144 -0.508)
			(end -0.9144 -0.406654)
			(stroke
				(width 0.1)
				(type default)
			)
			(layer "B.Fab")
		)
		(fp_line
			(start -0.9144 -0.406654)
			(end -1.1938 -0.406654)
			(stroke
				(width 0.1)
				(type default)
			)
			(layer "B.Fab")
		)
		(fp_line
			(start -0.9144 0.4064)
			(end -0.9144 0.508)
			(stroke
				(width 0.1)
				(type default)
			)
			(layer "B.Fab")
		)
		(fp_line
			(start -0.9144 0.508)
			(end 0.9144 0.508)
			(stroke
				(width 0.1)
				(type default)
			)
			(layer "B.Fab")
		)
		(fp_line
			(start 0.9144 -0.508)
			(end -0.9144 -0.508)
			(stroke
				(width 0.1)
				(type default)
			)
			(layer "B.Fab")
		)
		(fp_line
			(start 0.9144 -0.406654)
			(end 0.9144 -0.508)
			(stroke
				(width 0.1)
				(type default)
			)
			(layer "B.Fab")
		)
		(fp_line
			(start 0.9144 0.406654)
			(end 1.194308 0.406654)
			(stroke
				(width 0.1)
				(type default)
			)
			(layer "B.Fab")
		)
		(fp_line
			(start 0.9144 0.508)
			(end 0.9144 0.406654)
			(stroke
				(width 0.1)
				(type default)
			)
			(layer "B.Fab")
		)
		(fp_line
			(start 1.194308 -0.406654)
			(end 0.9144 -0.406654)
			(stroke
				(width 0.1)
				(type default)
			)
			(layer "B.Fab")
		)
		(fp_line
			(start 1.194308 0.406654)
			(end 1.194308 -0.406654)
			(stroke
				(width 0.1)
				(type default)
			)
			(layer "B.Fab")
		)
		(pad "1" smd rect
			(at 0.7366 0 270)
			(size 0.7112 0.8128)
			(layers "B.Cu" "B.Mask" "B.Paste")
			(net "P3V3_MAX11617_2_VDD")
		)
		(pad "2" smd rect
			(at -0.7366 0 270)
			(size 0.7112 0.8128)
			(layers "B.Cu" "B.Mask" "B.Paste")
			(net "P3V3_AUX")
		)
	)
	(footprint ""
		(layer "B.Cu")
		(at 130.218434 -388.011162 -90)
		(property "Reference" "C496"
			(at 0 0 90)
			(layer "B.SilkS")
			(hide yes)
			(effects
				(font
					(size 1.27 1.27)
				)
				(justify mirror)
			)
		)
		(property "Value" ""
			(at 0 0 90)
			(layer "B.Fab")
			(effects
				(font
					(size 1.27 1.27)
				)
				(justify mirror)
			)
		)
		(duplicate_pad_numbers_are_jumpers no)
		(fp_line
			(start -0.299974 0.150114)
			(end 0.299974 0.150114)
			(stroke
				(width 0.1)
				(type default)
			)
			(layer "B.Fab")
		)
		(fp_line
			(start 0.299974 0.150114)
			(end 0.299974 -0.150114)
			(stroke
				(width 0.1)
				(type default)
			)
			(layer "B.Fab")
		)
		(fp_line
			(start -0.299974 -0.150114)
			(end -0.299974 0.150114)
			(stroke
				(width 0.1)
				(type default)
			)
			(layer "B.Fab")
		)
		(fp_line
			(start 0.299974 -0.150114)
			(end -0.299974 -0.150114)
			(stroke
				(width 0.1)
				(type default)
			)
			(layer "B.Fab")
		)
		(pad "1" smd rect
			(at 0.2667 0 90)
			(size 0.3048 0.381)
			(layers "B.Cu" "B.Mask" "B.Paste")
			(net "P0V9_CPU1_RT3_2A")
		)
		(pad "2" smd rect
			(at -0.2667 0 90)
			(size 0.3048 0.381)
			(layers "B.Cu" "B.Mask" "B.Paste")
			(net "GND")
		)
	)
)
